(kicad_pcb
	(version 20221018)
	(generator pcbnew)
	(general
    (thickness 1.62)
  )
	(paper "A4")
	(title_block
    (title "ECP5 - Datacenter Secure Control Module (DC-SCM)")
    (date "2024-07-01")
    (rev "1.2.1")
		(comment 9 "footprints 210-211 of 506")
	)
	(layers
    (0 "F.Cu" signal)
    (1 "In1.Cu" power)
    (2 "In2.Cu" signal)
    (3 "In3.Cu" power)
    (4 "In4.Cu" power)
    (5 "In5.Cu" signal)
    (6 "In6.Cu" power)
    (31 "B.Cu" signal)
    (32 "B.Adhes" user "B.Adhesive")
    (33 "F.Adhes" user "F.Adhesive")
    (34 "B.Paste" user)
    (35 "F.Paste" user)
    (36 "B.SilkS" user "B.Silkscreen")
    (37 "F.SilkS" user "F.Silkscreen")
    (38 "B.Mask" user)
    (39 "F.Mask" user)
    (40 "Dwgs.User" user "User.Drawings")
    (41 "Cmts.User" user "User.Comments")
    (42 "Eco1.User" user "User.Eco1")
    (43 "Eco2.User" user "User.Eco2")
    (44 "Edge.Cuts" user)
    (45 "Margin" user)
    (46 "B.CrtYd" user "B.Courtyard")
    (47 "F.CrtYd" user "F.Courtyard")
    (48 "B.Fab" user)
    (49 "F.Fab" user)
  )
	(footprint "antmicro-footprints:HTSSOP-20_W4.4mm_P0.65mm" (layer "F.Cu")
    (at 90.94 67.455 -90)
    (property "Author" "Antmicro")
    (property "License" "Apache-2.0")
    (property "MPN" "LM21212MH-2/NOPB")
    (property "Manufacturer" "Texas Instruments")
    (property "Sheetfile" "power-supply.kicad_sch")
    (property "Sheetname" "Power supply")
    (property "ki_description" "DC-DC Switching Buck Step Down Regulator, Adjustable, 2.95V-5.5Vin, 600mV-5.5Vout, 12Aout, HTSSOP-20")
    (property "ki_keywords" "SMT, PMIC, IC, SWITCHING, BUCK, VOLTAGE, REGULATOR")
    (attr smd)
    (fp_text reference "U13" (at 1.13 -3.07 -90) (layer "F.SilkS")
        (effects (font (size 0.7 0.7) (thickness 0.15)) (justify left bottom))
    )
    (fp_text value "LM21212-2" (at 0.11 5.065 -90) (layer "F.Fab")
        (effects (font (size 0.7 0.7) (thickness 0.15)) (justify left bottom))
    )
    (fp_text user "${REFERENCE}" (at -3.84 6.699 -90) (layer "F.Fab") hide
        (effects (font (size 0.7 0.7) (thickness 0.15)) (justify left bottom))
    )
    (fp_text user "License: Apache-2.0" (at -3.84 9.099 -90) (layer "F.Fab") hide
        (effects (font (size 0.7 0.7) (thickness 0.15)) (justify left bottom))
    )
    (fp_text user "Author: Antmicro" (at -3.84 7.899 -90) (layer "F.Fab") hide
        (effects (font (size 0.7 0.7) (thickness 0.15)) (justify left bottom))
    )
    (fp_line (start -1.88 -3.3) (end 1.88 -3.3)
      (stroke (width 0.15) (type solid)) (layer "F.SilkS"))
    (fp_line (start -1.88 3.3) (end 1.88 3.3)
      (stroke (width 0.15) (type solid)) (layer "F.SilkS"))
    (fp_circle (center -2.97 -3.325) (end -2.92 -3.325)
      (stroke (width 0.15) (type solid)) (fill solid) (layer "F.SilkS"))
    (fp_rect (start -3.73 -3.875) (end 3.73 3.875)
      (stroke (width 0.05) (type solid)) (fill none) (layer "F.CrtYd"))
    (fp_line (start -2.25 -3.3) (end 2.25 -3.3)
      (stroke (width 0.15) (type solid)) (layer "F.Fab"))
    (fp_line (start -2.25 3.3) (end -2.25 -3.3)
      (stroke (width 0.15) (type solid)) (layer "F.Fab"))
    (fp_line (start -2.25 3.3) (end 2.25 3.3)
      (stroke (width 0.15) (type solid)) (layer "F.Fab"))
    (fp_line (start 2.25 3.3) (end 2.25 -3.3)
      (stroke (width 0.15) (type solid)) (layer "F.Fab"))
    (pad "1" smd roundrect (at -2.97 -2.925 180) (size 0.42 1.4) (layers "F.Cu" "F.Paste" "F.Mask") (roundrect_rratio 0.4399965333)
      (net 423 "Net-(U13-FADJ)") (pinfunction "FADJ") (pintype "passive"))
    (pad "2" smd roundrect (at -2.97 -2.275 180) (size 0.42 1.4) (layers "F.Cu" "F.Paste" "F.Mask") (roundrect_rratio 0.4399965333)
      (net 509 "unconnected-(U13-SS-Pad2)") (pinfunction "SS") (pintype "passive+no_connect"))
    (pad "3" smd roundrect (at -2.97 -1.625 180) (size 0.42 1.4) (layers "F.Cu" "F.Paste" "F.Mask") (roundrect_rratio 0.4399965333)
      (net 366 "/Power supply/VCCA0_EN") (pinfunction "EN") (pintype "passive"))
    (pad "4" smd roundrect (at -2.97 -0.975 180) (size 0.42 1.4) (layers "F.Cu" "F.Paste" "F.Mask") (roundrect_rratio 0.4399965333)
      (net 232 "Net-(U13-AVIN)") (pinfunction "AVIN") (pintype "passive"))
    (pad "5" smd roundrect (at -2.97 -0.325 180) (size 0.42 1.4) (layers "F.Cu" "F.Paste" "F.Mask") (roundrect_rratio 0.4399965333)
      (net 11 "VCC5V0") (pinfunction "PVIN") (pintype "passive"))
    (pad "6" smd roundrect (at -2.97 0.325 180) (size 0.42 1.4) (layers "F.Cu" "F.Paste" "F.Mask") (roundrect_rratio 0.4399965333)
      (net 11 "VCC5V0") (pinfunction "PVIN") (pintype "passive"))
    (pad "7" smd roundrect (at -2.97 0.975 180) (size 0.42 1.4) (layers "F.Cu" "F.Paste" "F.Mask") (roundrect_rratio 0.4399965333)
      (net 11 "VCC5V0") (pinfunction "PVIN") (pintype "passive"))
    (pad "8" smd roundrect (at -2.97 1.625 180) (size 0.42 1.4) (layers "F.Cu" "F.Paste" "F.Mask") (roundrect_rratio 0.4399965333)
      (net 1 "GND") (pinfunction "PGND") (pintype "passive"))
    (pad "9" smd roundrect (at -2.97 2.275 180) (size 0.42 1.4) (layers "F.Cu" "F.Paste" "F.Mask") (roundrect_rratio 0.4399965333)
      (net 1 "GND") (pinfunction "PGND") (pintype "passive"))
    (pad "10" smd roundrect (at -2.97 2.925 180) (size 0.42 1.4) (layers "F.Cu" "F.Paste" "F.Mask") (roundrect_rratio 0.4399965333)
      (net 1 "GND") (pinfunction "PGND") (pintype "passive"))
    (pad "11" smd roundrect (at 2.97 2.925 180) (size 0.42 1.4) (layers "F.Cu" "F.Paste" "F.Mask") (roundrect_rratio 0.4399965333)
      (net 234 "Net-(L1-Pad1)") (pinfunction "SW") (pintype "passive"))
    (pad "12" smd roundrect (at 2.97 2.275 180) (size 0.42 1.4) (layers "F.Cu" "F.Paste" "F.Mask") (roundrect_rratio 0.4399965333)
      (net 234 "Net-(L1-Pad1)") (pinfunction "SW") (pintype "passive"))
    (pad "13" smd roundrect (at 2.97 1.625 180) (size 0.42 1.4) (layers "F.Cu" "F.Paste" "F.Mask") (roundrect_rratio 0.4399965333)
      (net 234 "Net-(L1-Pad1)") (pinfunction "SW") (pintype "passive"))
    (pad "14" smd roundrect (at 2.97 0.975 180) (size 0.42 1.4) (layers "F.Cu" "F.Paste" "F.Mask") (roundrect_rratio 0.4399965333)
      (net 234 "Net-(L1-Pad1)") (pinfunction "SW") (pintype "passive"))
    (pad "15" smd roundrect (at 2.97 0.325 180) (size 0.42 1.4) (layers "F.Cu" "F.Paste" "F.Mask") (roundrect_rratio 0.4399965333)
      (net 234 "Net-(L1-Pad1)") (pinfunction "SW") (pintype "passive"))
    (pad "16" smd roundrect (at 2.97 -0.325 180) (size 0.42 1.4) (layers "F.Cu" "F.Paste" "F.Mask") (roundrect_rratio 0.4399965333)
      (net 234 "Net-(L1-Pad1)") (pinfunction "SW") (pintype "passive"))
    (pad "17" smd roundrect (at 2.97 -0.975 180) (size 0.42 1.4) (layers "F.Cu" "F.Paste" "F.Mask") (roundrect_rratio 0.4399965333)
      (net 235 "/Power supply/1V2_PG") (pinfunction "PGOOD") (pintype "passive"))
    (pad "18" smd roundrect (at 2.97 -1.625 180) (size 0.42 1.4) (layers "F.Cu" "F.Paste" "F.Mask") (roundrect_rratio 0.4399965333)
      (net 267 "Net-(U13-COMP)") (pinfunction "COMP") (pintype "passive"))
    (pad "19" smd roundrect (at 2.97 -2.275 180) (size 0.42 1.4) (layers "F.Cu" "F.Paste" "F.Mask") (roundrect_rratio 0.4399965333)
      (net 289 "Net-(U13-FB)") (pinfunction "FB") (pintype "passive"))
    (pad "20" smd roundrect (at 2.97 -2.925 180) (size 0.42 1.4) (layers "F.Cu" "F.Paste" "F.Mask") (roundrect_rratio 0.4399965333)
      (net 1 "GND") (pinfunction "AGND") (pintype "passive"))
    (pad "21" smd roundrect (at 0 0.37 270) (size 3.32 4.55) (layers "F.Cu" "F.Paste" "F.Mask") (roundrect_rratio 0.06)
      (net 1 "GND") (pinfunction "EP") (pintype "passive"))
  )
	(footprint "antmicro-footprints:Conn_Plug_Molex_SlimStack_2x25_529910508" locked (layer "F.Cu")
    (at 74.09468 156.3802)
    (property "Author" "Antmicro")
    (property "License" "Apache-2.0")
    (property "MPN" "529910508")
    (property "Manufacturer" "Molex")
    (property "Pitch " "0.5 mm")
    (property "Sheetfile" "rot.kicad_sch")
    (property "Sheetname" "RoT")
    (property "ki_description" "Mezzanine Connector, Receptacle, 0.5mm, 2Rows, 50Contacts, Surface Mount, Phosphor Bronze")
    (property "ki_keywords" "CONNECTOR, B2B, PLUG")
    (attr smd)
    (fp_text reference "J3" (at -8.49468 0.9348 90) (layer "F.SilkS")
        (effects (font (size 0.7 0.7) (thickness 0.15)) (justify left bottom))
    )
    (fp_text value "Plug_Molex_SlimStack_2x25_529910508" (at 0 4.75) (layer "F.Fab")
        (effects (font (size 0.7 0.7) (thickness 0.15)) (justify left bottom))
    )
    (fp_text user "License: Apache-2.0" (at -8.5 8.3) (layer "F.Fab") hide
        (effects (font (size 0.7 0.7) (thickness 0.15)) (justify left bottom))
    )
    (fp_text user "Author: Antmicro" (at -8.5 7.099) (layer "F.Fab") hide
        (effects (font (size 0.7 0.7) (thickness 0.15)) (justify left bottom))
    )
    (fp_text user "${REFERENCE}" (at -8.5 5.9) (layer "F.Fab") hide
        (effects (font (size 0.7 0.7) (thickness 0.15)) (justify left bottom))
    )
    (fp_line (start -8.15 -2.7) (end -8.15 2.7)
      (stroke (width 0.15) (type solid)) (layer "F.SilkS"))
    (fp_line (start -6.7 -2.7) (end -8.15 -2.7)
      (stroke (width 0.15) (type solid)) (layer "F.SilkS"))
    (fp_line (start -6.7 2.7) (end -8.15 2.7)
      (stroke (width 0.15) (type solid)) (layer "F.SilkS"))
    (fp_line (start 6.7 -2.7) (end 8.15 -2.7)
      (stroke (width 0.15) (type solid)) (layer "F.SilkS"))
    (fp_line (start 6.7 2.7) (end 8.15 2.7)
      (stroke (width 0.15) (type solid)) (layer "F.SilkS"))
    (fp_line (start 8.15 2.7) (end 8.15 -2.7)
      (stroke (width 0.15) (type solid)) (layer "F.SilkS"))
    (fp_circle (center -6.45 -3.05) (end -6.45 -3.1)
      (stroke (width 0.15) (type solid)) (fill solid) (layer "F.SilkS"))
    (fp_line (start -8.657 -3.399) (end -8.657 3.401)
      (stroke (width 0.05) (type solid)) (layer "F.CrtYd"))
    (fp_line (start -8.657 3.401) (end 8.643 3.401)
      (stroke (width 0.05) (type solid)) (layer "F.CrtYd"))
    (fp_line (start 8.643 -3.399) (end -8.657 -3.399)
      (stroke (width 0.05) (type solid)) (layer "F.CrtYd"))
    (fp_line (start 8.643 3.401) (end 8.643 -3.399)
      (stroke (width 0.05) (type solid)) (layer "F.CrtYd"))
    (pad "1" smd rect locked (at -6.007 -2.041 180) (size 0.3 1.8) (layers "F.Cu" "F.Paste" "F.Mask")
      (net 2 "VCC3V3") (pintype "passive"))
    (pad "2" smd rect locked (at -6.007 2.058 180) (size 0.3 1.8) (layers "F.Cu" "F.Paste" "F.Mask")
      (net 1 "GND") (pintype "passive"))
    (pad "3" smd rect locked (at -5.507 -2.041 180) (size 0.3 1.8) (layers "F.Cu" "F.Paste" "F.Mask")
      (net 2 "VCC3V3") (pintype "passive"))
    (pad "4" smd rect locked (at -5.507 2.058 180) (size 0.3 1.8) (layers "F.Cu" "F.Paste" "F.Mask")
      (net 1 "GND") (pintype "passive"))
    (pad "5" smd rect locked (at -5.006 -2.05 180) (size 0.3 1.8) (layers "F.Cu" "F.Paste" "F.Mask")
      (net 666 "ROT_GPIO1") (pintype "passive"))
    (pad "6" smd rect locked (at -5.006 2.058 180) (size 0.3 1.8) (layers "F.Cu" "F.Paste" "F.Mask")
      (net 665 "ROT_GPIO2") (pintype "passive"))
    (pad "7" smd rect locked (at -4.506 -2.041 180) (size 0.3 1.8) (layers "F.Cu" "F.Paste" "F.Mask")
      (net 91 "QSPI0_CS1_N") (pintype "passive"))
    (pad "8" smd rect locked (at -4.506 2.058 180) (size 0.3 1.8) (layers "F.Cu" "F.Paste" "F.Mask")
      (net 138 "QSPIA1_D2") (pintype "passive"))
    (pad "9" smd rect locked (at -4.007 -2.041 180) (size 0.3 1.8) (layers "F.Cu" "F.Paste" "F.Mask")
      (net 143 "QSPIA2_D2") (pintype "passive"))
    (pad "10" smd rect locked (at -4.007 2.058 180) (size 0.3 1.8) (layers "F.Cu" "F.Paste" "F.Mask")
      (net 137 "QSPIA1_D1") (pintype "passive"))
    (pad "11" smd rect locked (at -3.507 -2.041 180) (size 0.3 1.8) (layers "F.Cu" "F.Paste" "F.Mask")
      (net 142 "QSPIA2_D1") (pintype "passive"))
    (pad "12" smd rect locked (at -3.507 2.058 180) (size 0.3 1.8) (layers "F.Cu" "F.Paste" "F.Mask")
      (net 140 "QSPIA1_CS_N") (pintype "passive"))
    (pad "13" smd rect locked (at -3.007 -2.041 180) (size 0.3 1.8) (layers "F.Cu" "F.Paste" "F.Mask")
      (net 145 "QSPIA2_CS_N") (pintype "passive"))
    (pad "14" smd rect locked (at -3.007 2.058 180) (size 0.3 1.8) (layers "F.Cu" "F.Paste" "F.Mask")
      (net 139 "QSPIA1_D3") (pintype "passive"))
    (pad "15" smd rect locked (at -2.507 -2.041 180) (size 0.3 1.8) (layers "F.Cu" "F.Paste" "F.Mask")
      (net 144 "QSPIA2_D3") (pintype "passive"))
    (pad "16" smd rect locked (at -2.507 2.058 180) (size 0.3 1.8) (layers "F.Cu" "F.Paste" "F.Mask")
      (net 136 "QSPIA1_D0") (pintype "passive"))
    (pad "17" smd rect locked (at -2.005 -2.041 180) (size 0.3 1.8) (layers "F.Cu" "F.Paste" "F.Mask")
      (net 135 "QSPIA_CLK") (pintype "passive"))
    (pad "18" smd rect locked (at -2.005 2.058 180) (size 0.3 1.8) (layers "F.Cu" "F.Paste" "F.Mask")
      (net 68 "QSPI0_CLK") (pintype "passive"))
    (pad "19" smd rect locked (at -1.505 -2.041 180) (size 0.3 1.8) (layers "F.Cu" "F.Paste" "F.Mask")
      (net 141 "QSPIA2_D0") (pintype "passive"))
    (pad "20" smd rect locked (at -1.505 2.058 180) (size 0.3 1.8) (layers "F.Cu" "F.Paste" "F.Mask")
      (net 69 "QSPI0_CS0_N") (pintype "passive"))
    (pad "21" smd rect locked (at -1.005 -2.041 180) (size 0.3 1.8) (layers "F.Cu" "F.Paste" "F.Mask")
      (net 127 "QSPIB1_D2") (pintype "passive"))
    (pad "22" smd rect locked (at -1.005 2.058 180) (size 0.3 1.8) (layers "F.Cu" "F.Paste" "F.Mask")
      (net 70 "QSPI0_D0") (pintype "passive"))
    (pad "23" smd rect locked (at -0.505 -2.041 180) (size 0.3 1.8) (layers "F.Cu" "F.Paste" "F.Mask")
      (net 126 "QSPIB1_D1") (pintype "passive"))
    (pad "24" smd rect locked (at -0.505 2.058 180) (size 0.3 1.8) (layers "F.Cu" "F.Paste" "F.Mask")
      (net 71 "QSPI0_D1") (pintype "passive"))
    (pad "25" smd rect locked (at -0.005 -2.041 180) (size 0.3 1.8) (layers "F.Cu" "F.Paste" "F.Mask")
      (net 129 "QSPIB1_CS_N") (pintype "passive"))
    (pad "26" smd rect locked (at -0.005 2.058 180) (size 0.3 1.8) (layers "F.Cu" "F.Paste" "F.Mask")
      (net 72 "QSPI0_D2") (pintype "passive"))
    (pad "27" smd rect locked (at 0.493 -2.041 180) (size 0.3 1.8) (layers "F.Cu" "F.Paste" "F.Mask")
      (net 128 "QSPIB1_D3") (pintype "passive"))
    (pad "28" smd rect locked (at 0.493 2.058 180) (size 0.3 1.8) (layers "F.Cu" "F.Paste" "F.Mask")
      (net 73 "QSPI0_D3") (pintype "passive"))
    (pad "29" smd rect locked (at 0.994 -2.041 180) (size 0.3 1.8) (layers "F.Cu" "F.Paste" "F.Mask")
      (net 125 "QSPIB1_D0") (pintype "passive"))
    (pad "30" smd rect locked (at 0.994 2.058 180) (size 0.3 1.8) (layers "F.Cu" "F.Paste" "F.Mask")
      (net 272 "ROT_QSPI_SCK") (pintype "passive"))
    (pad "31" smd rect locked (at 1.494 -2.041 180) (size 0.3 1.8) (layers "F.Cu" "F.Paste" "F.Mask")
      (net 132 "QSPIB2_D2") (pintype "passive"))
    (pad "32" smd rect locked (at 1.494 2.058 180) (size 0.3 1.8) (layers "F.Cu" "F.Paste" "F.Mask")
      (net 273 "ROT_QSPI_DQ3") (pintype "passive"))
    (pad "33" smd rect locked (at 1.993 -2.041 180) (size 0.3 1.8) (layers "F.Cu" "F.Paste" "F.Mask")
      (net 131 "QSPIB2_D1") (pintype "passive"))
    (pad "34" smd rect locked (at 1.993 2.058 180) (size 0.3 1.8) (layers "F.Cu" "F.Paste" "F.Mask")
      (net 274 "ROT_QSPI_DQ2") (pintype "passive"))
    (pad "35" smd rect locked (at 2.493 -2.041 180) (size 0.3 1.8) (layers "F.Cu" "F.Paste" "F.Mask")
      (net 134 "QSPIB2_CS_N") (pintype "passive"))
    (pad "36" smd rect locked (at 2.493 2.058 180) (size 0.3 1.8) (layers "F.Cu" "F.Paste" "F.Mask")
      (net 275 "ROT_QSPI_DQ1") (pintype "passive"))
    (pad "37" smd rect locked (at 2.993 -2.041 180) (size 0.3 1.8) (layers "F.Cu" "F.Paste" "F.Mask")
      (net 133 "QSPIB2_D3") (pintype "passive"))
    (pad "38" smd rect locked (at 2.993 2.058 180) (size 0.3 1.8) (layers "F.Cu" "F.Paste" "F.Mask")
      (net 276 "ROT_QSPI_DQ0") (pintype "passive"))
    (pad "39" smd rect locked (at 3.493 -2.041 180) (size 0.3 1.8) (layers "F.Cu" "F.Paste" "F.Mask")
      (net 124 "QSPIB_CLK") (pintype "passive"))
    (pad "40" smd rect locked (at 3.493 2.058 180) (size 0.3 1.8) (layers "F.Cu" "F.Paste" "F.Mask")
      (net 268 "PROGRAM_N") (pintype "passive"))
    (pad "41" smd rect locked (at 3.994 -2.041 180) (size 0.3 1.8) (layers "F.Cu" "F.Paste" "F.Mask")
      (net 130 "QSPIB2_D0") (pintype "passive"))
    (pad "42" smd rect locked (at 3.994 2.058 180) (size 0.3 1.8) (layers "F.Cu" "F.Paste" "F.Mask")
      (net 269 "INIT_N") (pintype "passive"))
    (pad "43" smd rect locked (at 4.494 -2.041 180) (size 0.3 1.8) (layers "F.Cu" "F.Paste" "F.Mask")
      (net 271 "ROT_QSPI_CS_N") (pintype "passive"))
    (pad "44" smd rect locked (at 4.494 2.058 180) (size 0.3 1.8) (layers "F.Cu" "F.Paste" "F.Mask")
      (net 409 "ROT_RDY\\ROT_GPIO0") (pintype "passive"))
    (pad "45" smd rect locked (at 4.994 -2.041 180) (size 0.3 1.8) (layers "F.Cu" "F.Paste" "F.Mask")
      (net 661 "ROT_SS") (pintype "passive"))
    (pad "46" smd rect locked (at 4.994 2.058 180) (size 0.3 1.8) (layers "F.Cu" "F.Paste" "F.Mask")
      (net 662 "ROT_TX") (pintype "passive"))
    (pad "47" smd rect locked (at 5.494 -2.041 180) (size 0.3 1.8) (layers "F.Cu" "F.Paste" "F.Mask")
      (net 659 "ROT_MISO") (pintype "passive"))
    (pad "48" smd rect locked (at 5.494 2.058 180) (size 0.3 1.8) (layers "F.Cu" "F.Paste" "F.Mask")
      (net 663 "ROT_RX") (pintype "passive"))
    (pad "49" smd rect locked (at 5.994 -2.041 180) (size 0.3 1.8) (layers "F.Cu" "F.Paste" "F.Mask")
      (net 660 "ROT_MOSI") (pintype "passive"))
    (pad "50" smd rect locked (at 5.994 2.058 180) (size 0.3 1.8) (layers "F.Cu" "F.Paste" "F.Mask")
      (net 664 "ROT_SCLK") (pintype "passive"))
  )
)
